(kicad_pcb
	(version 20211014)
	(generator pcbnew)
	(general
    (thickness 1.6)
  )
	(paper "A4")
	(title_block
    (title "SA800U (Snapdragon 845) Baseboard")
    (date "2023-10-19")
    (rev "1.0.3")
    (company "Antmicro Ltd.")
    (comment 1 "www.antmicro.com")
		(comment 9 "footprints 90-96 of 589")
	)
	(layers
    (0 "F.Cu" signal)
    (1 "In1.Cu" power)
    (2 "In2.Cu" signal)
    (3 "In3.Cu" signal)
    (4 "In4.Cu" power)
    (31 "B.Cu" signal)
    (32 "B.Adhes" user "B.Adhesive")
    (33 "F.Adhes" user "F.Adhesive")
    (34 "B.Paste" user)
    (35 "F.Paste" user)
    (36 "B.SilkS" user "B.Silkscreen")
    (37 "F.SilkS" user "F.Silkscreen")
    (38 "B.Mask" user)
    (39 "F.Mask" user)
    (40 "Dwgs.User" user "User.Drawings")
    (41 "Cmts.User" user "User.Comments")
    (42 "Eco1.User" user "User.Eco1")
    (43 "Eco2.User" user "User.Eco2")
    (44 "Edge.Cuts" user)
    (45 "Margin" user)
    (46 "B.CrtYd" user "B.Courtyard")
    (47 "F.CrtYd" user "F.Courtyard")
    (48 "B.Fab" user)
    (49 "F.Fab" user)
  )
	(footprint "sa800u-baseboard-hw-footprints:AP62301WU-7-TSOT23-6" (layer "F.Cu")
    (tedit 6215EA50)
    (at 83.15 98.75 180)
    (property "Author" "Antmicro")
    (property "License" "Apache-2.0")
    (property "MPN" "AP62301WU-7")
    (property "Manufacturer" "Diodes Incorporated")
    (property "Sheetfile" "psu.kicad_sch")
    (property "Sheetname" "PSU")
    (attr smd)
    (fp_text reference "U19" (at -2.59 1.94 90) (layer "F.SilkS")
      (effects (font (size 0.7 0.7) (thickness 0.15)) (justify right bottom))
    )
    (fp_text value "AP62301WU-7" (at -0.005 2.6) (layer "F.Fab")
      (effects (font (size 0.7 0.7) (thickness 0.15)) (justify right bottom))
    )
    (fp_text user "License: Apache-2.0" (at -1.893 4.967) (layer "F.Fab") hide
      (effects (font (size 0.7 0.7) (thickness 0.15)) (justify right bottom))
    )
    (fp_text user "${REFERENCE}" (at -1.893 6.168) (layer "F.Fab") hide
      (effects (font (size 0.7 0.7) (thickness 0.15)) (justify right bottom))
    )
    (fp_text user "Author: Antmicro" (at -1.893 7.368) (layer "F.Fab") hide
      (effects (font (size 0.7 0.7) (thickness 0.15)) (justify right bottom))
    )
    (fp_line (start -1.4805 0.725) (end -1.4795 -0.725) (layer "F.SilkS") (width 0.15))
    (fp_line (start 1.479 0.73) (end 1.38 0.73) (layer "F.SilkS") (width 0.15))
    (fp_line (start -1.4805 0.725) (end -1.3905 0.725) (layer "F.SilkS") (width 0.15))
    (fp_line (start 1.48 -0.72) (end 1.38 -0.72) (layer "F.SilkS") (width 0.15))
    (fp_line (start 1.48 -0.72) (end 1.479 0.73) (layer "F.SilkS") (width 0.15))
    (fp_line (start -1.4795 -0.725) (end -1.3905 -0.725) (layer "F.SilkS") (width 0.15))
    (fp_circle (center -1.499 1.236) (end -1.45 1.236) (layer "F.SilkS") (width 0.15) (fill solid))
    (fp_rect (start -1.65 -1.61) (end 1.65 1.61) (layer "F.CrtYd") (width 0.05) (fill none))
    (fp_line (start -1.527 -0.833) (end 1.523 -0.833) (layer "F.Fab") (width 0.15))
    (fp_line (start 1.523 -0.833) (end 1.523 0.916) (layer "F.Fab") (width 0.15))
    (fp_line (start -1.527 0.491) (end -1.102 0.916) (layer "F.Fab") (width 0.15))
    (fp_line (start -1.527 0.491) (end -1.527 -0.833) (layer "F.Fab") (width 0.15))
    (fp_line (start -1.102 0.916) (end 1.523 0.916) (layer "F.Fab") (width 0.15))
    (pad "1" smd rect (at -0.952 1.18 180) (size 0.7 0.8) (layers "F.Cu" "F.Paste" "F.Mask")
      (net 1 "GND") (pinfunction "GND") (pintype "power_in"))
    (pad "2" smd rect (at -0.001 1.18 180) (size 0.7 0.8) (layers "F.Cu" "F.Paste" "F.Mask")
      (net 357 "Net-(C132-Pad2)") (pinfunction "SW") (pintype "power_out"))
    (pad "3" smd rect (at 0.947 1.18 180) (size 0.7 0.8) (layers "F.Cu" "F.Paste" "F.Mask")
      (net 74 "VDD") (pinfunction "VIN") (pintype "power_in"))
    (pad "4" smd rect (at 0.947 -1.18 180) (size 0.7 0.8) (layers "F.Cu" "F.Paste" "F.Mask")
      (net 171 "Net-(R135-Pad2)") (pinfunction "FB") (pintype "input"))
    (pad "5" smd rect (at -0.001 -1.18 180) (size 0.7 0.8) (layers "F.Cu" "F.Paste" "F.Mask")
      (net 409 "Net-(R131-Pad2)") (pinfunction "EN") (pintype "input"))
    (pad "6" smd rect (at -0.952 -1.18 180) (size 0.7 0.8) (layers "F.Cu" "F.Paste" "F.Mask")
      (net 356 "Net-(C132-Pad1)") (pinfunction "BST") (pintype "output"))
  )
	(footprint "sa800u-baseboard-hw-footprints:R_0402_1005Metric" (layer "F.Cu")
    (tedit 5FD9C158)
    (at 81.95 102.3)
    (descr "Resistor SMD 0402")
    (tags "resistor SMD 0402")
    (property "Author" "Antmicro")
    (property "License" "Apache-2.0")
    (property "MPN" "CR0402-FX-2002GLF")
    (property "Manufacturer" "Bourns")
    (property "Sheetfile" "psu.kicad_sch")
    (property "Sheetname" "PSU")
    (property "Tolerance" "1%")
    (property "Val" "20k")
    (attr smd)
    (fp_text reference "R136" (at 1.92 0.4) (layer "F.SilkS")
      (effects (font (size 0.7 0.7) (thickness 0.15)) (justify left bottom))
    )
    (fp_text value "R_20k_0402" (at 0 1.4) (layer "F.Fab")
      (effects (font (size 0.7 0.7) (thickness 0.15)) (justify left bottom))
    )
    (fp_text user "Author: Antmicro" (at -0.95 4.169) (layer "F.Fab") hide
      (effects (font (size 0.7 0.7) (thickness 0.15)) (justify left bottom))
    )
    (fp_text user "${REFERENCE}" (at -0.95 3.168) (layer "F.Fab") hide
      (effects (font (size 0.7 0.7) (thickness 0.15)) (justify left bottom))
    )
    (fp_text user "License: Apache-2.0" (at -0.95 5.169) (layer "F.Fab") hide
      (effects (font (size 0.7 0.7) (thickness 0.15)) (justify left bottom))
    )
    (fp_rect (start -0.93 -0.47) (end 0.93 0.47) (layer "F.CrtYd") (width 0.05) (fill none))
    (fp_rect (start -0.5 -0.25) (end 0.5 0.25) (layer "F.Fab") (width 0.15) (fill none))
    (pad "1" smd roundrect (at -0.485 0) (size 0.59 0.64) (layers "F.Cu" "F.Paste" "F.Mask") (roundrect_rratio 0.25)
      (net 1 "GND") (pintype "passive"))
    (pad "2" smd roundrect (at 0.485 0) (size 0.59 0.64) (layers "F.Cu" "F.Paste" "F.Mask") (roundrect_rratio 0.25)
      (net 171 "Net-(R135-Pad2)") (pintype "passive"))
  )
	(footprint "sa800u-baseboard-hw-footprints:L_Coilcraft_XEL4030" (layer "F.Cu")
    (tedit 6215D867)
    (at 78.8 118.02)
    (property "Author" "Antmicro")
    (property "IMax" "")
    (property "ISat" "")
    (property "License" "Apache-2.0")
    (property "MPN" "XEL4030-222MEC")
    (property "Manufacturer" "Coilcraft")
    (property "MaxCur" "6.1A")
    (property "Sheetfile" "psu.kicad_sch")
    (property "Sheetname" "PSU")
    (property "Size" "4x4")
    (property "Val" "2u2/6.1A")
    (attr smd)
    (fp_text reference "L29" (at -0.83 3.13) (layer "F.SilkS")
      (effects (font (size 0.7 0.7) (thickness 0.15)) (justify left bottom))
    )
    (fp_text value "L_2u2_6.1A_XEL4030" (at 0 3.35) (layer "F.Fab")
      (effects (font (size 0.7 0.7) (thickness 0.15)) (justify left bottom))
    )
    (fp_text user "${REFERENCE}" (at -2.15 4.996) (layer "F.Fab") hide
      (effects (font (size 0.7 0.7) (thickness 0.15)) (justify left bottom))
    )
    (fp_text user "Author: Antmicro" (at -2.15 5.996) (layer "F.Fab") hide
      (effects (font (size 0.7 0.7) (thickness 0.15)) (justify left bottom))
    )
    (fp_text user "License: Apache-2.0" (at -2.15 6.996) (layer "F.Fab") hide
      (effects (font (size 0.7 0.7) (thickness 0.15)) (justify left bottom))
    )
    (fp_line (start -1.8 2.2) (end 1.85 2.199) (layer "F.SilkS") (width 0.15))
    (fp_line (start -1.8 -2.2) (end 1.85 -2.201) (layer "F.SilkS") (width 0.15))
    (fp_rect (start -2.45 -2.45) (end 2.45 2.45) (layer "F.CrtYd") (width 0.05) (fill none))
    (fp_line (start 1.999 -2) (end 1.999 1.999) (layer "F.Fab") (width 0.15))
    (fp_line (start 1.999 1.999) (end -2 1.999) (layer "F.Fab") (width 0.15))
    (fp_line (start -2 1.999) (end -2 -2) (layer "F.Fab") (width 0.15))
    (fp_line (start -2 -2) (end 1.999 -2) (layer "F.Fab") (width 0.15))
    (pad "1" smd rect (at -1.186 0) (size 0.98 3.4) (layers "F.Cu" "F.Paste" "F.Mask")
      (net 363 "Net-(C138-Pad2)") (pintype "passive"))
    (pad "2" smd rect (at 1.185 0) (size 0.98 3.4) (layers "F.Cu" "F.Paste" "F.Mask")
      (net 133 "5V_SYS") (pintype "passive"))
  )
	(footprint "sa800u-baseboard-hw-footprints:C_0603_1608Metric" (layer "F.Cu")
    (tedit 5D5E94D2)
    (at 77 114.86)
    (descr "Capacitor SMD 0603")
    (tags "capacitor 0603")
    (property "Author" "Antmicro")
    (property "Dielectric" "")
    (property "License" "Apache-2.0")
    (property "MPN" "C1608X5R1E106M080AC")
    (property "Manufacturer" "TDK")
    (property "Sheetfile" "psu.kicad_sch")
    (property "Sheetname" "PSU")
    (property "Val" "10u/25V")
    (property "Voltage" "")
    (attr smd)
    (fp_text reference "C131" (at 1.05 0.35) (layer "F.SilkS")
      (effects (font (size 0.7 0.7) (thickness 0.15)) (justify left bottom))
    )
    (fp_text value "C_10u_25V_0603" (at 0 1.6) (layer "F.Fab")
      (effects (font (size 0.7 0.7) (thickness 0.15)) (justify left bottom))
    )
    (fp_text user "Author: Antmicro" (at -1.682 4.894) (layer "F.Fab") hide
      (effects (font (size 0.7 0.7) (thickness 0.15)) (justify left bottom))
    )
    (fp_text user "${REFERENCE}" (at -1.682 3.895) (layer "F.Fab") hide
      (effects (font (size 0.7 0.7) (thickness 0.15)) (justify left bottom))
    )
    (fp_text user "License: Apache-2.0" (at -1.682 5.895) (layer "F.Fab") hide
      (effects (font (size 0.7 0.7) (thickness 0.15)) (justify left bottom))
    )
    (fp_line (start -0.3 -0.3) (end 0.3 -0.3) (layer "F.SilkS") (width 0.15))
    (fp_line (start -0.3 0.3) (end 0.3 0.3) (layer "F.SilkS") (width 0.15))
    (fp_rect (start -1.24 -0.7) (end 1.24 0.7) (layer "F.CrtYd") (width 0.05) (fill none))
    (fp_rect (start -0.8 -0.4) (end 0.8 0.4) (layer "F.Fab") (width 0.15) (fill none))
    (pad "1" smd roundrect (at -0.7 0) (size 0.6 0.8) (layers "F.Cu" "F.Paste" "F.Mask") (roundrect_rratio 0.2)
      (net 74 "VDD") (pintype "passive"))
    (pad "2" smd roundrect (at 0.7 0) (size 0.6 0.8) (layers "F.Cu" "F.Paste" "F.Mask") (roundrect_rratio 0.2)
      (net 1 "GND") (pintype "passive"))
  )
	(footprint "sa800u-baseboard-hw-footprints:C_0402_1005Metric" (layer "F.Cu")
    (tedit 616D63CF)
    (at 72 119.6 -90)
    (descr "Capacitor SMD 0402")
    (tags "capacitor SMD 0402")
    (property "Author" "Antmicro")
    (property "Dielectric" "X5R")
    (property "License" "Apache-2.0")
    (property "MPN" "GRM155R61H104KE14D")
    (property "Manufacturer" "Murata")
    (property "Sheetfile" "psu.kicad_sch")
    (property "Sheetname" "PSU")
    (property "Val" "100n")
    (property "Voltage" "50V")
    (attr smd)
    (fp_text reference "C138" (at 3.73 -0.42 -90) (layer "F.SilkS")
      (effects (font (size 0.7 0.7) (thickness 0.15)) (justify left bottom))
    )
    (fp_text value "C_100n_0402" (at 0 1.4 -90) (layer "F.Fab")
      (effects (font (size 0.7 0.7) (thickness 0.15)) (justify left bottom))
    )
    (fp_text user "${REFERENCE}" (at -0.932 3.168 -90) (layer "F.Fab") hide
      (effects (font (size 0.7 0.7) (thickness 0.15)) (justify left bottom))
    )
    (fp_text user "License: Apache-2.0" (at -0.932 5.17 -90) (layer "F.Fab") hide
      (effects (font (size 0.7 0.7) (thickness 0.15)) (justify left bottom))
    )
    (fp_text user "Author: Antmicro" (at -0.932 4.17 -90) (layer "F.Fab") hide
      (effects (font (size 0.7 0.7) (thickness 0.15)) (justify left bottom))
    )
    (fp_rect (start -0.94 -0.47) (end 0.94 0.47) (layer "F.CrtYd") (width 0.05) (fill none))
    (fp_rect (start -0.499 -0.249) (end 0.499 0.249) (layer "F.Fab") (width 0.15) (fill none))
    (pad "1" smd roundrect (at -0.484 0 270) (size 0.59 0.64) (layers "F.Cu" "F.Paste" "F.Mask") (roundrect_rratio 0.25)
      (net 362 "Net-(C138-Pad1)") (pintype "passive"))
    (pad "2" smd roundrect (at 0.484 0 270) (size 0.59 0.64) (layers "F.Cu" "F.Paste" "F.Mask") (roundrect_rratio 0.25)
      (net 363 "Net-(C138-Pad2)") (pintype "passive"))
  )
	(footprint "sa800u-baseboard-hw-footprints:C_0603_1608Metric" (layer "F.Cu")
    (tedit 5D5E94D2)
    (at 83.47 120.05 -90)
    (descr "Capacitor SMD 0603")
    (tags "capacitor 0603")
    (property "Author" "Antmicro")
    (property "Dielectric" "")
    (property "License" "Apache-2.0")
    (property "MPN" "GRM188R60J226MEA0D")
    (property "Manufacturer" "Murata")
    (property "Sheetfile" "psu.kicad_sch")
    (property "Sheetname" "PSU")
    (property "Val" "22u")
    (property "Voltage" "")
    (attr smd)
    (fp_text reference "C142" (at 1.29 -2.52 -90) (layer "F.SilkS")
      (effects (font (size 0.7 0.7) (thickness 0.15)) (justify left bottom))
    )
    (fp_text value "C_22u_0603" (at 0 1.6 -90) (layer "F.Fab")
      (effects (font (size 0.7 0.7) (thickness 0.15)) (justify left bottom))
    )
    (fp_text user "Author: Antmicro" (at -1.682 4.894 -90) (layer "F.Fab") hide
      (effects (font (size 0.7 0.7) (thickness 0.15)) (justify left bottom))
    )
    (fp_text user "License: Apache-2.0" (at -1.682 5.895 -90) (layer "F.Fab") hide
      (effects (font (size 0.7 0.7) (thickness 0.15)) (justify left bottom))
    )
    (fp_text user "${REFERENCE}" (at -1.682 3.895 -90) (layer "F.Fab") hide
      (effects (font (size 0.7 0.7) (thickness 0.15)) (justify left bottom))
    )
    (fp_line (start -0.3 -0.3) (end 0.3 -0.3) (layer "F.SilkS") (width 0.15))
    (fp_line (start -0.3 0.3) (end 0.3 0.3) (layer "F.SilkS") (width 0.15))
    (fp_rect (start -1.24 -0.7) (end 1.24 0.7) (layer "F.CrtYd") (width 0.05) (fill none))
    (fp_rect (start -0.8 -0.4) (end 0.8 0.4) (layer "F.Fab") (width 0.15) (fill none))
    (pad "1" smd roundrect (at -0.7 0 270) (size 0.6 0.8) (layers "F.Cu" "F.Paste" "F.Mask") (roundrect_rratio 0.2)
      (net 133 "5V_SYS") (pintype "passive"))
    (pad "2" smd roundrect (at 0.7 0 270) (size 0.6 0.8) (layers "F.Cu" "F.Paste" "F.Mask") (roundrect_rratio 0.2)
      (net 1 "GND") (pintype "passive"))
  )
	(footprint "sa800u-baseboard-hw-footprints:UQFN-12_2x1.7mm_P0.4mm_Texas_RUT" (layer "F.Cu")
    (tedit 5F354333)
    (at 110.3 138.1 -90)
    (descr "Texas_R_PUQFN-N12")
    (tags "Texas_R_PUQFN-N12")
    (property "Author" "Antmicro")
    (property "License" "Apache-2.0")
    (property "MPN" "TXB0104RUTR")
    (property "Manufacturer" "Texas Instruments")
    (property "Sheetfile" "usb-c-interface.kicad_sch")
    (property "Sheetname" "USB-C Interface ")
    (attr smd)
    (fp_text reference "U8" (at -1.26 0.8) (layer "F.SilkS")
      (effects (font (size 0.7 0.7) (thickness 0.15)) (justify left bottom))
    )
    (fp_text value "TXB0104_UQFN" (at 0 2.35 -90) (layer "F.Fab")
      (effects (font (size 0.7 0.7) (thickness 0.15)) (justify left bottom))
    )
    (fp_text user "Author: Antmicro" (at -1.1 4.35 -90) (layer "F.Fab") hide
      (effects (font (size 0.7 0.7) (thickness 0.15)) (justify left bottom))
    )
    (fp_text user "License: Apache-2.0" (at -1.1 6.75 -90) (layer "F.Fab") hide
      (effects (font (size 0.7 0.7) (thickness 0.15)) (justify left bottom))
    )
    (fp_text user "${REFERENCE}" (at -1.1 5.55 -90) (layer "F.Fab") hide
      (effects (font (size 0.7 0.7) (thickness 0.15)) (justify left bottom))
    )
    (fp_line (start 0.597 -1.301) (end -0.55 -1.301) (layer "F.SilkS") (width 0.15))
    (fp_line (start 0.497 1.3) (end -0.5 1.3) (layer "F.SilkS") (width 0.15))
    (fp_circle (center -0.85 -1.2) (end -0.8 -1.2) (layer "F.SilkS") (width 0.15) (fill solid))
    (fp_rect (start -1.1 -1.3) (end 1.1 1.3) (layer "F.CrtYd") (width 0.05) (fill none))
    (fp_line (start 0.847 -1) (end 0.847 0.997) (layer "F.Fab") (width 0.15))
    (fp_line (start -0.5 -1) (end -0.85 -0.5) (layer "F.Fab") (width 0.15))
    (fp_line (start -0.85 0.997) (end -0.85 -0.5) (layer "F.Fab") (width 0.15))
    (fp_line (start -0.5 -1) (end 0.847 -1) (layer "F.Fab") (width 0.15))
    (fp_line (start 0.847 0.997) (end -0.85 0.997) (layer "F.Fab") (width 0.15))
    (pad "1" smd rect (at -0.653 -0.803 180) (size 0.2 0.6) (layers "F.Cu" "F.Paste" "F.Mask")
      (net 134 "1V8_SYS") (pinfunction "VCCA") (pintype "power_in"))
    (pad "1" smd rect (at -0.425 -0.975 270) (size 0.15 0.25) (layers "F.Cu" "F.Paste" "F.Mask")
      (net 134 "1V8_SYS") (pinfunction "VCCA") (pintype "power_in"))
    (pad "2" smd rect (at -0.653 -0.403 180) (size 0.2 0.6) (layers "F.Cu" "F.Paste" "F.Mask")
      (net 99 "USB2_SINK") (pinfunction "A1") (pintype "tri_state"))
    (pad "3" smd rect (at -0.653 0 180) (size 0.2 0.6) (layers "F.Cu" "F.Paste" "F.Mask")
      (net 100 "USB2_FAULT") (pinfunction "A2") (pintype "tri_state"))
    (pad "4" smd rect (at -0.653 0.4 180) (size 0.2 0.6) (layers "F.Cu" "F.Paste" "F.Mask")
      (net 101 "USB2_EN") (pinfunction "A3") (pintype "tri_state"))
    (pad "5" smd rect (at -0.653 0.8 180) (size 0.2 0.6) (layers "F.Cu" "F.Paste" "F.Mask")
      (net 506 "unconnected-(U8-Pad5)") (pinfunction "A4") (pintype "tri_state+no_connect"))
    (pad "6" smd rect (at 0 0.8 180) (size 0.6 0.2) (layers "F.Cu" "F.Paste" "F.Mask")
      (net 1 "GND") (pinfunction "GND") (pintype "power_in"))
    (pad "7" smd rect (at 0.65 0.8 180) (size 0.2 0.6) (layers "F.Cu" "F.Paste" "F.Mask")
      (net 505 "unconnected-(U8-Pad7)") (pinfunction "B4") (pintype "tri_state+no_connect"))
    (pad "8" smd rect (at 0.65 0.4 180) (size 0.2 0.6) (layers "F.Cu" "F.Paste" "F.Mask")
      (net 301 "/USB-C Interface /USB2_EN_5V") (pinfunction "B3") (pintype "tri_state"))
    (pad "9" smd rect (at 0.65 0 180) (size 0.2 0.6) (layers "F.Cu" "F.Paste" "F.Mask")
      (net 292 "/USB-C Interface /USB2_FAULT_5V") (pinfunction "B2") (pintype "tri_state"))
    (pad "10" smd rect (at 0.65 -0.403 180) (size 0.2 0.6) (layers "F.Cu" "F.Paste" "F.Mask")
      (net 291 "/USB-C Interface /USB2_SINK_5V") (pinfunction "B1") (pintype "tri_state"))
    (pad "11" smd rect (at 0.65 -0.803 180) (size 0.2 0.6) (layers "F.Cu" "F.Paste" "F.Mask")
      (net 133 "5V_SYS") (pinfunction "VCCB") (pintype "power_in"))
    (pad "12" smd rect (at 0 -0.803 180) (size 0.6 0.2) (layers "F.Cu" "F.Paste" "F.Mask")
      (net 134 "1V8_SYS") (pinfunction "OE") (pintype "input"))
  )
)
